#ISCELL
  pure_quanta quanta_title_block_c *
  *
#ISCELL
  pure_quanta_power cad_note *
  *
#CELL
  pure_quanta genoa_sp5 *
  page40_i159
#ISCELL
  mstr_standard offpage *
  page40_i160
#ISCELL
  mstr_standard offpage *
  page40_i161
#ISCELL
  mstr_standard tap *
  page40_i162
#ISCELL
  mstr_standard tap *
  page40_i163
#ISCELL
  mstr_standard tap *
  page40_i164
#ISCELL
  mstr_standard tap *
  page40_i165
#ISCELL
  mstr_standard tap *
  page40_i166
#ISCELL
  mstr_standard tap *
  page40_i167
#ISCELL
  mstr_standard tap *
  page40_i168
#ISCELL
  mstr_standard tap *
  page40_i169
#ISCELL
  mstr_standard tap *
  page40_i170
#ISCELL
  mstr_standard tap *
  page40_i171
#ISCELL
  mstr_standard tap *
  page40_i172
#ISCELL
  mstr_standard tap *
  page40_i173
#ISCELL
  mstr_standard tap *
  page40_i174
#ISCELL
  mstr_standard tap *
  page40_i175
#ISCELL
  mstr_standard tap *
  page40_i176
#ISCELL
  mstr_standard tap *
  page40_i177
#ISCELL
  mstr_standard tap *
  page40_i178
#ISCELL
  mstr_standard tap *
  page40_i179
#ISCELL
  mstr_standard tap *
  page40_i180
#ISCELL
  mstr_standard tap *
  page40_i181
#ISCELL
  mstr_standard tap *
  page40_i182
#ISCELL
  mstr_standard tap *
  page40_i183
#ISCELL
  mstr_standard tap *
  page40_i184
#ISCELL
  mstr_standard tap *
  page40_i185
#ISCELL
  mstr_standard tap *
  page40_i186
#ISCELL
  mstr_standard tap *
  page40_i187
#ISCELL
  mstr_standard tap *
  page40_i188
#ISCELL
  mstr_standard tap *
  page40_i189
#ISCELL
  mstr_standard tap *
  page40_i190
#ISCELL
  mstr_standard tap *
  page40_i191
#ISCELL
  mstr_standard tap *
  page40_i192
#ISCELL
  mstr_standard tap *
  page40_i193
#ISCELL
  mstr_standard tap *
  page40_i194
#ISCELL
  mstr_standard tap *
  page40_i195
#ISCELL
  mstr_standard tap *
  page40_i196
#ISCELL
  mstr_standard offpage *
  page40_i197
#ISCELL
  mstr_standard tap *
  page40_i198
#ISCELL
  mstr_standard tap *
  page40_i199
#ISCELL
  mstr_standard tap *
  page40_i200
#ISCELL
  mstr_standard tap *
  page40_i201
#ISCELL
  mstr_standard tap *
  page40_i202
#ISCELL
  mstr_standard tap *
  page40_i203
#ISCELL
  mstr_standard tap *
  page40_i204
#ISCELL
  mstr_standard tap *
  page40_i205
#ISCELL
  mstr_standard tap *
  page40_i206
#ISCELL
  mstr_standard tap *
  page40_i207
#ISCELL
  mstr_standard tap *
  page40_i208
#ISCELL
  mstr_standard tap *
  page40_i209
#ISCELL
  mstr_standard tap *
  page40_i210
#ISCELL
  mstr_standard tap *
  page40_i211
#ISCELL
  mstr_standard tap *
  page40_i212
#ISCELL
  mstr_standard tap *
  page40_i213
#ISCELL
  mstr_standard tap *
  page40_i214
#ISCELL
  mstr_standard tap *
  page40_i215
#ISCELL
  mstr_standard tap *
  page40_i216
#ISCELL
  mstr_standard tap *
  page40_i217
#ISCELL
  mstr_standard tap *
  page40_i218
#ISCELL
  mstr_standard tap *
  page40_i219
#ISCELL
  mstr_standard tap *
  page40_i220
#ISCELL
  mstr_standard tap *
  page40_i221
#ISCELL
  mstr_standard tap *
  page40_i222
#ISCELL
  mstr_standard tap *
  page40_i223
#ISCELL
  mstr_standard tap *
  page40_i224
#ISCELL
  mstr_standard tap *
  page40_i225
#ISCELL
  mstr_standard tap *
  page40_i226
#ISCELL
  mstr_standard tap *
  page40_i227
#ISCELL
  mstr_standard tap *
  page40_i228
#ISCELL
  mstr_standard tap *
  page40_i229
#ISCELL
  mstr_standard tap *
  page40_i230
#ISCELL
  mstr_standard tap *
  page40_i231
#ISCELL
  mstr_standard tap *
  page40_i232
#ISCELL
  mstr_standard tap *
  page40_i233
#ISCELL
  mstr_standard tap *
  page40_i234
#ISCELL
  mstr_standard offpage *
  page40_i235
#ISCELL
  mstr_standard tap *
  page40_i236
#ISCELL
  mstr_standard tap *
  page40_i237
#ISCELL
  mstr_standard tap *
  page40_i238
#ISCELL
  mstr_standard tap *
  page40_i239
#ISCELL
  mstr_standard tap *
  page40_i240
#ISCELL
  mstr_standard tap *
  page40_i241
#ISCELL
  mstr_standard tap *
  page40_i242
#ISCELL
  mstr_standard tap *
  page40_i243
#ISCELL
  mstr_standard tap *
  page40_i244
#ISCELL
  mstr_standard tap *
  page40_i245
#ISCELL
  mstr_standard tap *
  page40_i246
#ISCELL
  mstr_standard tap *
  page40_i247
#ISCELL
  mstr_standard tap *
  page40_i248
#ISCELL
  mstr_standard tap *
  page40_i249
#ISCELL
  mstr_standard tap *
  page40_i250
#ISCELL
  mstr_standard tap *
  page40_i251
#ISCELL
  mstr_standard tap *
  page40_i252
#ISCELL
  mstr_standard tap *
  page40_i253
#ISCELL
  mstr_standard tap *
  page40_i254
#ISCELL
  mstr_standard tap *
  page40_i255
#ISCELL
  mstr_standard tap *
  page40_i256
#ISCELL
  mstr_standard tap *
  page40_i257
#ISCELL
  mstr_standard tap *
  page40_i258
#ISCELL
  mstr_standard tap *
  page40_i259
#ISCELL
  mstr_standard tap *
  page40_i260
#ISCELL
  mstr_standard tap *
  page40_i261
#ISCELL
  mstr_standard tap *
  page40_i262
#ISCELL
  mstr_standard tap *
  page40_i263
#ISCELL
  mstr_standard tap *
  page40_i264
#ISCELL
  mstr_standard tap *
  page40_i265
#ISCELL
  mstr_standard tap *
  page40_i266
#ISCELL
  mstr_standard tap *
  page40_i267
#ISCELL
  mstr_standard tap *
  page40_i268
#ISCELL
  mstr_standard tap *
  page40_i269
#ISCELL
  mstr_standard tap *
  page40_i270
#ISCELL
  mstr_standard tap *
  page40_i271
#ISCELL
  mstr_standard tap *
  page40_i272
#ISCELL
  mstr_standard tap *
  page40_i273
#ISCELL
  mstr_standard tap *
  page40_i274
#ISCELL
  mstr_standard tap *
  page40_i275
#ISCELL
  mstr_standard tap *
  page40_i276
#ISCELL
  mstr_standard tap *
  page40_i277
#ISCELL
  mstr_standard tap *
  page40_i278
#ISCELL
  mstr_standard tap *
  page40_i279
#ISCELL
  mstr_standard tap *
  page40_i280
#ISCELL
  mstr_standard tap *
  page40_i281
#ISCELL
  standard offpage *
  page40_i282
#ISCELL
  standard offpage *
  page40_i283
#ISCELL
  standard offpage *
  page40_i284
#ISCELL
  standard offpage *
  page40_i285
#ISCELL
  mstr_standard tap *
  page40_i286
#ISCELL
  mstr_standard tap *
  page40_i287
#ISCELL
  mstr_standard tap *
  page40_i288
#ISCELL
  mstr_standard tap *
  page40_i289
#ISCELL
  mstr_standard tap *
  page40_i290
#ISCELL
  mstr_standard tap *
  page40_i291
#ISCELL
  mstr_standard tap *
  page40_i292
#ISCELL
  mstr_standard tap *
  page40_i293
#ISCELL
  mstr_standard tap *
  page40_i294
#ISCELL
  mstr_standard tap *
  page40_i295
#ISCELL
  mstr_standard tap *
  page40_i296
#ISCELL
  mstr_standard tap *
  page40_i297
#ISCELL
  mstr_standard tap *
  page40_i298
#ISCELL
  mstr_standard tap *
  page40_i299
#ISCELL
  mstr_standard tap *
  page40_i300
#ISCELL
  mstr_standard tap *
  page40_i301
#ISCELL
  standard offpage *
  page40_i302
#ISCELL
  standard offpage *
  page40_i303
#ISCELL
  standard offpage *
  page40_i304
#ISCELL
  standard offpage *
  page40_i305
#ISCELL
  standard offpage *
  page40_i306
#ISCELL
  standard offpage *
  page40_i307
#ISCELL
  standard offpage *
  page40_i308
#ISCELL
  mstr_standard offpage *
  page40_i309
#ISCELL
  standard offpage *
  page40_i310
#ISCELL
  standard offpage *
  page40_i311
#ISCELL
  standard offpage *
  page40_i312
#ISCELL
  standard offpage *
  page40_i313
#CELL
  pure_quanta q_res *
  page40_i314
#ISCELL
  mstr_standard offpage *
  page40_i315
#ISCELL
  standard offpage *
  page40_i316
